# S9S_MB_2U (Grand Teton) — schematic netlist excerpt (pin names and nets, part order shuffled) for the footprints in the layout excerpt that follows; sources: Cadence DE-HDL packaged netlist, KiCad conversion of 03242023_DA0F0TMBIJ0_F0T_Motherboard_J_brd_V01_OCP.brd

D99  Q_LED  IC  pkg SMLF  page 252 : A = LED_P3V3 ; C = GND
R1396  Q_RES  10K 1% CHIP  pkg 0402LF  page 190 : A = FM_M2_SSD_0_PEDET ; B = P3V3_AUX

(kicad_pcb
	(version 20260206)
	(generator "pcbnew")
	(generator_version "10.0")
	(general
		(thickness 1.6)
		(legacy_teardrops no)
	)
	(paper "A4")
	(title_block
		(title "03242023_DA0F0TMBIJ0_F0T_Motherboard_J_brd_V01_OCP.brd")
		(comment 1 "Grand Teton / footprints 1906-1907 of 6105")
	)
	(layers
		(0 "F.Cu" signal "TOP")
		(4 "In1.Cu" signal "GND")
		(6 "In2.Cu" signal "IN1")
		(8 "In3.Cu" signal "GND1")
		(10 "In4.Cu" signal "IN2")
		(12 "In5.Cu" signal "GND2")
		(14 "In6.Cu" signal "IN3")
		(16 "In7.Cu" signal "GND3")
		(18 "In8.Cu" signal "VCC")
		(20 "In9.Cu" signal "VCC1")
		(22 "In10.Cu" signal "GND4")
		(24 "In11.Cu" signal "IN4")
		(26 "In12.Cu" signal "GND5")
		(28 "In13.Cu" signal "IN5")
		(30 "In14.Cu" signal "GND6")
		(32 "In15.Cu" signal "IN6")
		(34 "In16.Cu" signal "GND7")
		(2 "B.Cu" signal "BOTTOM")
		(9 "F.Adhes" user "F.Adhesive")
		(11 "B.Adhes" user "B.Adhesive")
		(13 "F.Paste" user "Package Geometry/Pastemask Top")
		(15 "B.Paste" user "Package Geometry/Pastemask Bottom")
		(5 "F.SilkS" user "Ref Des/Silkscreen Top")
		(7 "B.SilkS" user "Ref Des/Silkscreen Bottom")
		(1 "F.Mask" user "Board Geometry/Soldermask Top")
		(3 "B.Mask" user "Board Geometry/Soldermask Bottom")
		(17 "Dwgs.User" user "User.Drawings")
		(19 "Cmts.User" user "User.Comments")
		(21 "Eco1.User" user "User.Eco1")
		(23 "Eco2.User" user "User.Eco2")
		(25 "Edge.Cuts" user "Board Geometry/Outline")
		(27 "Margin" user)
		(31 "F.CrtYd" user "Package Geometry/Place Bound Top")
		(29 "B.CrtYd" user "Package Geometry/Place Bound Bottom")
		(35 "F.Fab" user "Ref Des/Assembly Top")
		(33 "B.Fab" user "Ref Des/Assembly Bottom")
	)
	(footprint ""
		(layer "F.Cu")
		(at 180.77688 -39.969948)
		(property "Reference" "R1396"
			(at 0 0 0)
			(layer "F.SilkS")
			(hide yes)
			(effects
				(font
					(size 1.27 1.27)
				)
			)
		)
		(property "Value" ""
			(at 0 0 0)
			(layer "F.Fab")
			(effects
				(font
					(size 1.27 1.27)
				)
			)
		)
		(duplicate_pad_numbers_are_jumpers no)
		(fp_line
			(start -0.7874 -0.4064)
			(end 0.7874 -0.4064)
			(stroke
				(width 0.1524)
				(type default)
			)
			(layer "F.SilkS")
		)
		(fp_line
			(start -0.7874 0.4064)
			(end -0.7874 -0.4064)
			(stroke
				(width 0.1524)
				(type default)
			)
			(layer "F.SilkS")
		)
		(fp_line
			(start 0.7874 -0.4064)
			(end 0.7874 0.4064)
			(stroke
				(width 0.1524)
				(type default)
			)
			(layer "F.SilkS")
		)
		(fp_line
			(start 0.7874 0.4064)
			(end -0.7874 0.4064)
			(stroke
				(width 0.1524)
				(type default)
			)
			(layer "F.SilkS")
		)
		(fp_line
			(start -0.67945 -0.305054)
			(end -0.12065 -0.305054)
			(stroke
				(width 0.1)
				(type default)
			)
			(layer "F.Fab")
		)
		(fp_line
			(start -0.67945 0.3048)
			(end -0.67945 -0.305054)
			(stroke
				(width 0.1)
				(type default)
			)
			(layer "F.Fab")
		)
		(fp_line
			(start -0.12065 -0.305054)
			(end -0.12065 -0.2794)
			(stroke
				(width 0.1)
				(type default)
			)
			(layer "F.Fab")
		)
		(fp_line
			(start -0.12065 -0.2794)
			(end 0.12065 -0.2794)
			(stroke
				(width 0.1)
				(type default)
			)
			(layer "F.Fab")
		)
		(fp_line
			(start -0.12065 0.2794)
			(end -0.12065 0.3048)
			(stroke
				(width 0.1)
				(type default)
			)
			(layer "F.Fab")
		)
		(fp_line
			(start -0.12065 0.3048)
			(end -0.67945 0.3048)
			(stroke
				(width 0.1)
				(type default)
			)
			(layer "F.Fab")
		)
		(fp_line
			(start 0.120396 0.2794)
			(end -0.12065 0.2794)
			(stroke
				(width 0.1)
				(type default)
			)
			(layer "F.Fab")
		)
		(fp_line
			(start 0.120396 0.3048)
			(end 0.120396 0.2794)
			(stroke
				(width 0.1)
				(type default)
			)
			(layer "F.Fab")
		)
		(fp_line
			(start 0.12065 -0.3048)
			(end 0.67945 -0.3048)
			(stroke
				(width 0.1)
				(type default)
			)
			(layer "F.Fab")
		)
		(fp_line
			(start 0.12065 -0.2794)
			(end 0.12065 -0.3048)
			(stroke
				(width 0.1)
				(type default)
			)
			(layer "F.Fab")
		)
		(fp_line
			(start 0.67945 -0.3048)
			(end 0.67945 0.3048)
			(stroke
				(width 0.1)
				(type default)
			)
			(layer "F.Fab")
		)
		(fp_line
			(start 0.67945 0.3048)
			(end 0.120396 0.3048)
			(stroke
				(width 0.1)
				(type default)
			)
			(layer "F.Fab")
		)
		(pad "1" smd circle
			(at -0.40005 0)
			(size 0 0)
			(layers "F.Cu" "F.Mask" "F.Paste")
			(net "FM_M2_SSD_0_PEDET")
		)
		(pad "2" smd circle
			(at 0.40005 0)
			(size 0 0)
			(layers "F.Cu" "F.Mask" "F.Paste")
			(net "P3V3_AUX")
		)
	)
	(footprint ""
		(layer "F.Cu")
		(at 87.196676 -79.078836)
		(property "Reference" "D99"
			(at -44.30141 38.649402 90)
			(unlocked yes)
			(layer "F.SilkS")
			(effects
				(font
					(size 0.635 0.4064)
					(thickness 0.1524)
				)
				(justify left)
			)
		)
		(property "Value" ""
			(at 0 0 0)
			(layer "F.Fab")
			(effects
				(font
					(size 1.27 1.27)
				)
			)
		)
		(duplicate_pad_numbers_are_jumpers no)
		(fp_line
			(start -0.90678 0.4826)
			(end -0.90678 -0.4699)
			(stroke
				(width 0.1524)
				(type default)
			)
			(layer "F.SilkS")
		)
		(fp_line
			(start -0.89408 -0.4826)
			(end 0.90678 -0.4826)
			(stroke
				(width 0.1524)
				(type default)
			)
			(layer "F.SilkS")
		)
		(fp_line
			(start -0.79248 -0.4826)
			(end 1.03378 -0.4826)
			(stroke
				(width 0.1524)
				(type default)
			)
			(layer "F.SilkS")
		)
		(fp_line
			(start -0.64008 -0.4826)
			(end 1.16078 -0.4826)
			(stroke
				(width 0.1524)
				(type default)
			)
			(layer "F.SilkS")
		)
		(fp_line
			(start 0.90678 -0.4826)
			(end 0.90678 0.4826)
			(stroke
				(width 0.1524)
				(type default)
			)
			(layer "F.SilkS")
		)
		(fp_line
			(start 0.90678 0.4826)
			(end -0.90678 0.4826)
			(stroke
				(width 0.1524)
				(type default)
			)
			(layer "F.SilkS")
		)
		(fp_line
			(start 1.03378 -0.4826)
			(end 1.03378 0.4826)
			(stroke
				(width 0.1524)
				(type default)
			)
			(layer "F.SilkS")
		)
		(fp_line
			(start 1.03378 0.4826)
			(end -0.79248 0.4826)
			(stroke
				(width 0.1524)
				(type default)
			)
			(layer "F.SilkS")
		)
		(fp_line
			(start 1.16078 -0.4826)
			(end 1.16078 0.4826)
			(stroke
				(width 0.1524)
				(type default)
			)
			(layer "F.SilkS")
		)
		(fp_line
			(start 1.16078 0.4826)
			(end -0.64008 0.4826)
			(stroke
				(width 0.1524)
				(type default)
			)
			(layer "F.SilkS")
		)
		(fp_line
			(start -0.499872 -0.249936)
			(end 0.499872 -0.249936)
			(stroke
				(width 0.1)
				(type default)
			)
			(layer "F.Fab")
		)
		(fp_line
			(start -0.499872 0.249936)
			(end -0.499872 -0.249936)
			(stroke
				(width 0.1)
				(type default)
			)
			(layer "F.Fab")
		)
		(fp_line
			(start 0.499872 -0.249936)
			(end 0.499872 0.249936)
			(stroke
				(width 0.1)
				(type default)
			)
			(layer "F.Fab")
		)
		(fp_line
			(start 0.499872 0.249936)
			(end -0.499872 0.249936)
			(stroke
				(width 0.1)
				(type default)
			)
			(layer "F.Fab")
		)
		(pad "A" smd rect
			(at -0.47498 0)
			(size 0.6096 0.7112)
			(layers "F.Cu" "F.Mask" "F.Paste")
			(net "LED_P3V3")
		)
		(pad "C" smd rect
			(at 0.47498 0)
			(size 0.6096 0.7112)
			(layers "F.Cu" "F.Mask" "F.Paste")
			(net "GND")
		)
	)
)
